# T6G (Grand Teton) — schematic netlist excerpt (pin names and nets, part order shuffled) for the footprints in the layout excerpt that follows; sources: Cadence DE-HDL packaged netlist, KiCad conversion of 04192023_DAF0TMB3IC0_F0TG_MB_C_brd_V02_OCP.brd

C2363  Q_CAP  22UF 4V 20% X6S  pkg C0402  page 73 : A = PVDDCR_CPU1_P1 ; B = GND
PC527_2  Q_CAP  22UF 4V 20% X6S  pkg C0805  page 225 : A = PVDD11_S3_P1 ; B = GND
PC472  Q_CAP  470PF 50V 10% X7R  pkg 0402  page 193 : A = PVDDCR_SOC_P0_TEMP1 ; B = GND

(kicad_pcb
	(version 20260206)
	(generator "pcbnew")
	(generator_version "10.0")
	(general
		(thickness 1.6)
		(legacy_teardrops no)
	)
	(paper "A4")
	(title_block
		(title "04192023_DAF0TMB3IC0_F0TG_MB_C_brd_V02_OCP.brd")
		(comment 1 "Grand Teton / footprints 5087-5089 of 8354")
	)
	(layers
		(0 "F.Cu" signal "TOP")
		(4 "In1.Cu" signal "GND")
		(6 "In2.Cu" signal "IN1")
		(8 "In3.Cu" signal "GND1")
		(10 "In4.Cu" signal "IN2")
		(12 "In5.Cu" signal "GND2")
		(14 "In6.Cu" signal "IN3")
		(16 "In7.Cu" signal "GND3")
		(18 "In8.Cu" signal "VCC")
		(20 "In9.Cu" signal "VCC1")
		(22 "In10.Cu" signal "GND4")
		(24 "In11.Cu" signal "IN4")
		(26 "In12.Cu" signal "GND5")
		(28 "In13.Cu" signal "IN5")
		(30 "In14.Cu" signal "GND6")
		(32 "In15.Cu" signal "IN6")
		(34 "In16.Cu" signal "GND7")
		(2 "B.Cu" signal "BOTTOM")
		(9 "F.Adhes" user "F.Adhesive")
		(11 "B.Adhes" user "B.Adhesive")
		(13 "F.Paste" user "Package Geometry/Pastemask Top")
		(15 "B.Paste" user "Package Geometry/Pastemask Bottom")
		(5 "F.SilkS" user "Ref Des/Silkscreen Top")
		(7 "B.SilkS" user "Ref Des/Silkscreen Bottom")
		(1 "F.Mask" user "Board Geometry/Soldermask Top")
		(3 "B.Mask" user "Board Geometry/Soldermask Bottom")
		(17 "Dwgs.User" user "User.Drawings")
		(19 "Cmts.User" user "User.Comments")
		(21 "Eco1.User" user "User.Eco1")
		(23 "Eco2.User" user "User.Eco2")
		(25 "Edge.Cuts" user "Board Geometry/Outline")
		(27 "Margin" user)
		(31 "F.CrtYd" user "Package Geometry/Place Bound Top")
		(29 "B.CrtYd" user "Package Geometry/Place Bound Bottom")
		(35 "F.Fab" user "Ref Des/Assembly Top")
		(33 "B.Fab" user "Ref Des/Assembly Bottom")
	)
	(footprint ""
		(layer "B.Cu")
		(at 186.758834 -342.261952 -90)
		(property "Reference" "PC527_2"
			(at 0 0 90)
			(layer "B.SilkS")
			(hide yes)
			(effects
				(font
					(size 1.27 1.27)
				)
				(justify mirror)
			)
		)
		(property "Value" ""
			(at 0 0 90)
			(layer "B.Fab")
			(effects
				(font
					(size 1.27 1.27)
				)
				(justify mirror)
			)
		)
		(duplicate_pad_numbers_are_jumpers no)
		(fp_line
			(start -1.524 0.762)
			(end 1.524 0.762)
			(stroke
				(width 0.1524)
				(type default)
			)
			(layer "B.SilkS")
		)
		(fp_line
			(start 1.524 0.762)
			(end 1.524 -0.762)
			(stroke
				(width 0.1524)
				(type default)
			)
			(layer "B.SilkS")
		)
		(fp_line
			(start -1.524 -0.762)
			(end -1.524 0.762)
			(stroke
				(width 0.1524)
				(type default)
			)
			(layer "B.SilkS")
		)
		(fp_line
			(start 1.524 -0.762)
			(end -1.524 -0.762)
			(stroke
				(width 0.1524)
				(type default)
			)
			(layer "B.SilkS")
		)
		(fp_line
			(start -1.1049 0.724916)
			(end -1.1049 -0.724916)
			(stroke
				(width 0.1)
				(type default)
			)
			(layer "B.Fab")
		)
		(fp_line
			(start 1.1049 0.724916)
			(end -1.1049 0.724916)
			(stroke
				(width 0.1)
				(type default)
			)
			(layer "B.Fab")
		)
		(fp_line
			(start -1.1049 -0.724916)
			(end 1.1049 -0.724916)
			(stroke
				(width 0.1)
				(type default)
			)
			(layer "B.Fab")
		)
		(fp_line
			(start 1.1049 -0.724916)
			(end 1.1049 0.724916)
			(stroke
				(width 0.1)
				(type default)
			)
			(layer "B.Fab")
		)
		(pad "1" smd rect
			(at 0.889 0 270)
			(size 1.016 1.27)
			(layers "B.Cu" "B.Mask" "B.Paste")
			(net "PVDD11_S3_P1")
		)
		(pad "2" smd rect
			(at -0.889 0 270)
			(size 1.016 1.27)
			(layers "B.Cu" "B.Mask" "B.Paste")
			(net "GND")
		)
	)
	(footprint ""
		(layer "B.Cu")
		(at 384.113278 -142.234158 180)
		(property "Reference" "PC472"
			(at 0 0 0)
			(layer "B.SilkS")
			(hide yes)
			(effects
				(font
					(size 1.27 1.27)
				)
				(justify mirror)
			)
		)
		(property "Value" ""
			(at 0 0 0)
			(layer "B.Fab")
			(effects
				(font
					(size 1.27 1.27)
				)
				(justify mirror)
			)
		)
		(duplicate_pad_numbers_are_jumpers no)
		(fp_line
			(start 0.7874 0.4064)
			(end 0.7874 -0.4064)
			(stroke
				(width 0.1524)
				(type default)
			)
			(layer "B.SilkS")
		)
		(fp_line
			(start 0.7874 -0.4064)
			(end -0.7874 -0.4064)
			(stroke
				(width 0.1524)
				(type default)
			)
			(layer "B.SilkS")
		)
		(fp_line
			(start -0.7874 0.4064)
			(end 0.7874 0.4064)
			(stroke
				(width 0.1524)
				(type default)
			)
			(layer "B.SilkS")
		)
		(fp_line
			(start -0.7874 -0.4064)
			(end -0.7874 0.4064)
			(stroke
				(width 0.1524)
				(type default)
			)
			(layer "B.SilkS")
		)
		(fp_line
			(start 0.67945 0.3048)
			(end 0.67945 -0.305054)
			(stroke
				(width 0.1)
				(type default)
			)
			(layer "B.Fab")
		)
		(fp_line
			(start 0.67945 -0.305054)
			(end 0.12065 -0.305054)
			(stroke
				(width 0.1)
				(type default)
			)
			(layer "B.Fab")
		)
		(fp_line
			(start 0.12065 0.3048)
			(end 0.67945 0.3048)
			(stroke
				(width 0.1)
				(type default)
			)
			(layer "B.Fab")
		)
		(fp_line
			(start 0.12065 0.2794)
			(end 0.12065 0.3048)
			(stroke
				(width 0.1)
				(type default)
			)
			(layer "B.Fab")
		)
		(fp_line
			(start 0.12065 -0.2794)
			(end -0.12065 -0.2794)
			(stroke
				(width 0.1)
				(type default)
			)
			(layer "B.Fab")
		)
		(fp_line
			(start 0.12065 -0.305054)
			(end 0.12065 -0.2794)
			(stroke
				(width 0.1)
				(type default)
			)
			(layer "B.Fab")
		)
		(fp_line
			(start -0.120396 0.3048)
			(end -0.120396 0.2794)
			(stroke
				(width 0.1)
				(type default)
			)
			(layer "B.Fab")
		)
		(fp_line
			(start -0.120396 0.2794)
			(end 0.12065 0.2794)
			(stroke
				(width 0.1)
				(type default)
			)
			(layer "B.Fab")
		)
		(fp_line
			(start -0.12065 -0.2794)
			(end -0.12065 -0.3048)
			(stroke
				(width 0.1)
				(type default)
			)
			(layer "B.Fab")
		)
		(fp_line
			(start -0.12065 -0.3048)
			(end -0.67945 -0.3048)
			(stroke
				(width 0.1)
				(type default)
			)
			(layer "B.Fab")
		)
		(fp_line
			(start -0.67945 0.3048)
			(end -0.120396 0.3048)
			(stroke
				(width 0.1)
				(type default)
			)
			(layer "B.Fab")
		)
		(fp_line
			(start -0.67945 -0.3048)
			(end -0.67945 0.3048)
			(stroke
				(width 0.1)
				(type default)
			)
			(layer "B.Fab")
		)
		(pad "1" smd circle
			(at 0.40005 0)
			(size 0 0)
			(layers "B.Cu" "B.Mask" "B.Paste")
			(net "PVDDCR_SOC_P0_TEMP1")
		)
		(pad "2" smd circle
			(at -0.40005 0)
			(size 0 0)
			(layers "B.Cu" "B.Mask" "B.Paste")
			(net "GND")
		)
	)
	(footprint ""
		(layer "B.Cu")
		(at 124.173234 -269.313152 180)
		(property "Reference" "C2363"
			(at 0 0 0)
			(layer "B.SilkS")
			(hide yes)
			(effects
				(font
					(size 1.27 1.27)
				)
				(justify mirror)
			)
		)
		(property "Value" ""
			(at 0 0 0)
			(layer "B.Fab")
			(effects
				(font
					(size 1.27 1.27)
				)
				(justify mirror)
			)
		)
		(duplicate_pad_numbers_are_jumpers no)
		(fp_line
			(start 0.7874 0.4064)
			(end 0.7874 -0.4064)
			(stroke
				(width 0.1524)
				(type default)
			)
			(layer "B.SilkS")
		)
		(fp_line
			(start 0.7874 -0.4064)
			(end -0.7874 -0.4064)
			(stroke
				(width 0.1524)
				(type default)
			)
			(layer "B.SilkS")
		)
		(fp_line
			(start -0.7874 0.4064)
			(end 0.7874 0.4064)
			(stroke
				(width 0.1524)
				(type default)
			)
			(layer "B.SilkS")
		)
		(fp_line
			(start -0.7874 -0.4064)
			(end -0.7874 0.4064)
			(stroke
				(width 0.1524)
				(type default)
			)
			(layer "B.SilkS")
		)
		(fp_line
			(start 0.67945 0.3048)
			(end 0.67945 -0.305054)
			(stroke
				(width 0.1)
				(type default)
			)
			(layer "B.Fab")
		)
		(fp_line
			(start 0.67945 -0.305054)
			(end 0.12065 -0.305054)
			(stroke
				(width 0.1)
				(type default)
			)
			(layer "B.Fab")
		)
		(fp_line
			(start 0.12065 0.3048)
			(end 0.67945 0.3048)
			(stroke
				(width 0.1)
				(type default)
			)
			(layer "B.Fab")
		)
		(fp_line
			(start 0.12065 0.2794)
			(end 0.12065 0.3048)
			(stroke
				(width 0.1)
				(type default)
			)
			(layer "B.Fab")
		)
		(fp_line
			(start 0.12065 -0.2794)
			(end -0.12065 -0.2794)
			(stroke
				(width 0.1)
				(type default)
			)
			(layer "B.Fab")
		)
		(fp_line
			(start 0.12065 -0.305054)
			(end 0.12065 -0.2794)
			(stroke
				(width 0.1)
				(type default)
			)
			(layer "B.Fab")
		)
		(fp_line
			(start -0.120396 0.3048)
			(end -0.120396 0.2794)
			(stroke
				(width 0.1)
				(type default)
			)
			(layer "B.Fab")
		)
		(fp_line
			(start -0.120396 0.2794)
			(end 0.12065 0.2794)
			(stroke
				(width 0.1)
				(type default)
			)
			(layer "B.Fab")
		)
		(fp_line
			(start -0.12065 -0.2794)
			(end -0.12065 -0.3048)
			(stroke
				(width 0.1)
				(type default)
			)
			(layer "B.Fab")
		)
		(fp_line
			(start -0.12065 -0.3048)
			(end -0.67945 -0.3048)
			(stroke
				(width 0.1)
				(type default)
			)
			(layer "B.Fab")
		)
		(fp_line
			(start -0.67945 0.3048)
			(end -0.120396 0.3048)
			(stroke
				(width 0.1)
				(type default)
			)
			(layer "B.Fab")
		)
		(fp_line
			(start -0.67945 -0.3048)
			(end -0.67945 0.3048)
			(stroke
				(width 0.1)
				(type default)
			)
			(layer "B.Fab")
		)
		(pad "1" smd circle
			(at 0.40005 0)
			(size 0 0)
			(layers "B.Cu" "B.Mask" "B.Paste")
			(net "PVDDCR_CPU1_P1")
		)
		(pad "2" smd circle
			(at -0.40005 0)
			(size 0 0)
			(layers "B.Cu" "B.Mask" "B.Paste")
			(net "GND")
		)
	)
)
